(kicad_pcb
	(version 20260206)
	(generator "pcbnew")
	(generator_version "10.0")
	(general
		(thickness 1.6)
		(legacy_teardrops no)
	)
	(paper "A4")
	(title_block
		(title "01162023_DA0F0TEBIF0_F0T_Expander_BD_F_brd_V02_OCP.brd")
		(comment 1 "Grand Teton / footprints 9114-9121 of 9728")
	)
	(layers
		(0 "F.Cu" signal "TOP")
		(4 "In1.Cu" signal "GND")
		(6 "In2.Cu" signal "VCC")
		(8 "In3.Cu" signal "VCC1")
		(10 "In4.Cu" signal "GND1")
		(12 "In5.Cu" signal "IN1")
		(14 "In6.Cu" signal "GND2")
		(16 "In7.Cu" signal "IN2")
		(18 "In8.Cu" signal "GND3")
		(20 "In9.Cu" signal "IN3")
		(22 "In10.Cu" signal "GND4")
		(24 "In11.Cu" signal "IN4")
		(26 "In12.Cu" signal "GND5")
		(28 "In13.Cu" signal "IN5")
		(30 "In14.Cu" signal "GND6")
		(32 "In15.Cu" signal "IN6")
		(34 "In16.Cu" signal "GND7")
		(2 "B.Cu" signal "BOTTOM")
		(9 "F.Adhes" user "F.Adhesive")
		(11 "B.Adhes" user "B.Adhesive")
		(13 "F.Paste" user "Package Geometry/Pastemask Top")
		(15 "B.Paste" user "Package Geometry/Pastemask Bottom")
		(5 "F.SilkS" user "Ref Des/Silkscreen Top")
		(7 "B.SilkS" user "Ref Des/Silkscreen Bottom")
		(1 "F.Mask" user "Board Geometry/Soldermask Top")
		(3 "B.Mask" user "Board Geometry/Soldermask Bottom")
		(17 "Dwgs.User" user "User.Drawings")
		(19 "Cmts.User" user "User.Comments")
		(21 "Eco1.User" user "User.Eco1")
		(23 "Eco2.User" user "User.Eco2")
		(25 "Edge.Cuts" user "Board Geometry/Outline")
		(27 "Margin" user)
		(31 "F.CrtYd" user "Package Geometry/Place Bound Top")
		(29 "B.CrtYd" user "Package Geometry/Place Bound Bottom")
		(35 "F.Fab" user "Ref Des/Assembly Top")
		(33 "B.Fab" user "Ref Des/Assembly Bottom")
	)
	(footprint ""
		(layer "B.Cu")
		(at 71.049896 -298.27474 180)
		(property "Reference" "C2925"
			(at 0 0 0)
			(layer "B.SilkS")
			(hide yes)
			(effects
				(font
					(size 1.27 1.27)
				)
				(justify mirror)
			)
		)
		(property "Value" ""
			(at 0 0 0)
			(layer "B.Fab")
			(effects
				(font
					(size 1.27 1.27)
				)
				(justify mirror)
			)
		)
		(duplicate_pad_numbers_are_jumpers no)
		(fp_line
			(start 0.299974 0.150114)
			(end 0.299974 -0.150114)
			(stroke
				(width 0.1)
				(type default)
			)
			(layer "B.Fab")
		)
		(fp_line
			(start 0.299974 -0.150114)
			(end -0.299974 -0.150114)
			(stroke
				(width 0.1)
				(type default)
			)
			(layer "B.Fab")
		)
		(fp_line
			(start -0.299974 0.150114)
			(end 0.299974 0.150114)
			(stroke
				(width 0.1)
				(type default)
			)
			(layer "B.Fab")
		)
		(fp_line
			(start -0.299974 -0.150114)
			(end -0.299974 0.150114)
			(stroke
				(width 0.1)
				(type default)
			)
			(layer "B.Fab")
		)
		(pad "1" smd rect
			(at 0.2667 0)
			(size 0.3048 0.381)
			(layers "B.Cu" "B.Mask" "B.Paste")
			(net "P1V25_PEX0")
		)
		(pad "2" smd rect
			(at -0.2667 0)
			(size 0.3048 0.381)
			(layers "B.Cu" "B.Mask" "B.Paste")
			(net "GND")
		)
	)
	(footprint ""
		(layer "B.Cu")
		(at 235.14177 -212.332824 90)
		(property "Reference" "C195"
			(at 0 0 90)
			(layer "B.SilkS")
			(hide yes)
			(effects
				(font
					(size 1.27 1.27)
				)
				(justify mirror)
			)
		)
		(property "Value" ""
			(at 0 0 90)
			(layer "B.Fab")
			(effects
				(font
					(size 1.27 1.27)
				)
				(justify mirror)
			)
		)
		(duplicate_pad_numbers_are_jumpers no)
		(fp_line
			(start 0.7874 -0.4064)
			(end -0.7874 -0.4064)
			(stroke
				(width 0.1524)
				(type default)
			)
			(layer "B.SilkS")
		)
		(fp_line
			(start -0.7874 -0.4064)
			(end -0.7874 0.4064)
			(stroke
				(width 0.1524)
				(type default)
			)
			(layer "B.SilkS")
		)
		(fp_line
			(start 0.7874 0.4064)
			(end 0.7874 -0.4064)
			(stroke
				(width 0.1524)
				(type default)
			)
			(layer "B.SilkS")
		)
		(fp_line
			(start -0.7874 0.4064)
			(end 0.7874 0.4064)
			(stroke
				(width 0.1524)
				(type default)
			)
			(layer "B.SilkS")
		)
		(fp_line
			(start 0.67945 -0.305054)
			(end 0.12065 -0.305054)
			(stroke
				(width 0.1)
				(type default)
			)
			(layer "B.Fab")
		)
		(fp_line
			(start 0.12065 -0.305054)
			(end 0.12065 -0.2794)
			(stroke
				(width 0.1)
				(type default)
			)
			(layer "B.Fab")
		)
		(fp_line
			(start -0.12065 -0.3048)
			(end -0.67945 -0.3048)
			(stroke
				(width 0.1)
				(type default)
			)
			(layer "B.Fab")
		)
		(fp_line
			(start -0.67945 -0.3048)
			(end -0.67945 0.3048)
			(stroke
				(width 0.1)
				(type default)
			)
			(layer "B.Fab")
		)
		(fp_line
			(start 0.12065 -0.2794)
			(end -0.12065 -0.2794)
			(stroke
				(width 0.1)
				(type default)
			)
			(layer "B.Fab")
		)
		(fp_line
			(start -0.12065 -0.2794)
			(end -0.12065 -0.3048)
			(stroke
				(width 0.1)
				(type default)
			)
			(layer "B.Fab")
		)
		(fp_line
			(start 0.12065 0.2794)
			(end 0.12065 0.3048)
			(stroke
				(width 0.1)
				(type default)
			)
			(layer "B.Fab")
		)
		(fp_line
			(start -0.120396 0.2794)
			(end 0.12065 0.2794)
			(stroke
				(width 0.1)
				(type default)
			)
			(layer "B.Fab")
		)
		(fp_line
			(start 0.67945 0.3048)
			(end 0.67945 -0.305054)
			(stroke
				(width 0.1)
				(type default)
			)
			(layer "B.Fab")
		)
		(fp_line
			(start 0.12065 0.3048)
			(end 0.67945 0.3048)
			(stroke
				(width 0.1)
				(type default)
			)
			(layer "B.Fab")
		)
		(fp_line
			(start -0.120396 0.3048)
			(end -0.120396 0.2794)
			(stroke
				(width 0.1)
				(type default)
			)
			(layer "B.Fab")
		)
		(fp_line
			(start -0.67945 0.3048)
			(end -0.120396 0.3048)
			(stroke
				(width 0.1)
				(type default)
			)
			(layer "B.Fab")
		)
		(pad "1" smd circle
			(at 0.40005 0 270)
			(size 0 0)
			(layers "B.Cu" "B.Mask" "B.Paste")
			(net "P1V2_AUX_SCALED")
		)
		(pad "2" smd circle
			(at -0.40005 0 270)
			(size 0 0)
			(layers "B.Cu" "B.Mask" "B.Paste")
			(net "GND")
		)
	)
	(footprint ""
		(layer "B.Cu")
		(at 182.39994 -288.299906 90)
		(property "Reference" "C3106"
			(at 0 0 90)
			(layer "B.SilkS")
			(hide yes)
			(effects
				(font
					(size 1.27 1.27)
				)
				(justify mirror)
			)
		)
		(property "Value" ""
			(at 0 0 90)
			(layer "B.Fab")
			(effects
				(font
					(size 1.27 1.27)
				)
				(justify mirror)
			)
		)
		(duplicate_pad_numbers_are_jumpers no)
		(fp_line
			(start 0.299974 -0.150114)
			(end -0.299974 -0.150114)
			(stroke
				(width 0.1)
				(type default)
			)
			(layer "B.Fab")
		)
		(fp_line
			(start -0.299974 -0.150114)
			(end -0.299974 0.150114)
			(stroke
				(width 0.1)
				(type default)
			)
			(layer "B.Fab")
		)
		(fp_line
			(start 0.299974 0.150114)
			(end 0.299974 -0.150114)
			(stroke
				(width 0.1)
				(type default)
			)
			(layer "B.Fab")
		)
		(fp_line
			(start -0.299974 0.150114)
			(end 0.299974 0.150114)
			(stroke
				(width 0.1)
				(type default)
			)
			(layer "B.Fab")
		)
		(pad "1" smd rect
			(at 0.2667 0 270)
			(size 0.3048 0.381)
			(layers "B.Cu" "B.Mask" "B.Paste")
			(net "P1V25_PEX1")
		)
		(pad "2" smd rect
			(at -0.2667 0 270)
			(size 0.3048 0.381)
			(layers "B.Cu" "B.Mask" "B.Paste")
			(net "GND")
		)
	)
	(footprint ""
		(layer "B.Cu")
		(at 177.174906 -286.399732 90)
		(property "Reference" "C3131"
			(at 0 0 90)
			(layer "B.SilkS")
			(hide yes)
			(effects
				(font
					(size 1.27 1.27)
				)
				(justify mirror)
			)
		)
		(property "Value" ""
			(at 0 0 90)
			(layer "B.Fab")
			(effects
				(font
					(size 1.27 1.27)
				)
				(justify mirror)
			)
		)
		(duplicate_pad_numbers_are_jumpers no)
		(fp_line
			(start 0.299974 -0.150114)
			(end -0.299974 -0.150114)
			(stroke
				(width 0.1)
				(type default)
			)
			(layer "B.Fab")
		)
		(fp_line
			(start -0.299974 -0.150114)
			(end -0.299974 0.150114)
			(stroke
				(width 0.1)
				(type default)
			)
			(layer "B.Fab")
		)
		(fp_line
			(start 0.299974 0.150114)
			(end 0.299974 -0.150114)
			(stroke
				(width 0.1)
				(type default)
			)
			(layer "B.Fab")
		)
		(fp_line
			(start -0.299974 0.150114)
			(end 0.299974 0.150114)
			(stroke
				(width 0.1)
				(type default)
			)
			(layer "B.Fab")
		)
		(pad "1" smd rect
			(at 0.2667 0 270)
			(size 0.3048 0.381)
			(layers "B.Cu" "B.Mask" "B.Paste")
			(net "P1V25_SERDES_VDDPLL_PEX1")
		)
		(pad "2" smd rect
			(at -0.2667 0 270)
			(size 0.3048 0.381)
			(layers "B.Cu" "B.Mask" "B.Paste")
			(net "GND")
		)
	)
	(footprint ""
		(layer "B.Cu")
		(at 324.612 -83.947 180)
		(property "Reference" "R6264"
			(at 0 0 0)
			(layer "B.SilkS")
			(hide yes)
			(effects
				(font
					(size 1.27 1.27)
				)
				(justify mirror)
			)
		)
		(property "Value" ""
			(at 0 0 0)
			(layer "B.Fab")
			(effects
				(font
					(size 1.27 1.27)
				)
				(justify mirror)
			)
		)
		(duplicate_pad_numbers_are_jumpers no)
		(fp_line
			(start 0.7874 0.4064)
			(end 0.7874 -0.4064)
			(stroke
				(width 0.1524)
				(type default)
			)
			(layer "B.SilkS")
		)
		(fp_line
			(start 0.7874 -0.4064)
			(end -0.7874 -0.4064)
			(stroke
				(width 0.1524)
				(type default)
			)
			(layer "B.SilkS")
		)
		(fp_line
			(start -0.7874 0.4064)
			(end 0.7874 0.4064)
			(stroke
				(width 0.1524)
				(type default)
			)
			(layer "B.SilkS")
		)
		(fp_line
			(start -0.7874 -0.4064)
			(end -0.7874 0.4064)
			(stroke
				(width 0.1524)
				(type default)
			)
			(layer "B.SilkS")
		)
		(fp_line
			(start 0.67945 0.3048)
			(end 0.67945 -0.305054)
			(stroke
				(width 0.1)
				(type default)
			)
			(layer "B.Fab")
		)
		(fp_line
			(start 0.67945 -0.305054)
			(end 0.12065 -0.305054)
			(stroke
				(width 0.1)
				(type default)
			)
			(layer "B.Fab")
		)
		(fp_line
			(start 0.12065 0.3048)
			(end 0.67945 0.3048)
			(stroke
				(width 0.1)
				(type default)
			)
			(layer "B.Fab")
		)
		(fp_line
			(start 0.12065 0.2794)
			(end 0.12065 0.3048)
			(stroke
				(width 0.1)
				(type default)
			)
			(layer "B.Fab")
		)
		(fp_line
			(start 0.12065 -0.2794)
			(end -0.12065 -0.2794)
			(stroke
				(width 0.1)
				(type default)
			)
			(layer "B.Fab")
		)
		(fp_line
			(start 0.12065 -0.305054)
			(end 0.12065 -0.2794)
			(stroke
				(width 0.1)
				(type default)
			)
			(layer "B.Fab")
		)
		(fp_line
			(start -0.120396 0.3048)
			(end -0.120396 0.2794)
			(stroke
				(width 0.1)
				(type default)
			)
			(layer "B.Fab")
		)
		(fp_line
			(start -0.120396 0.2794)
			(end 0.12065 0.2794)
			(stroke
				(width 0.1)
				(type default)
			)
			(layer "B.Fab")
		)
		(fp_line
			(start -0.12065 -0.2794)
			(end -0.12065 -0.3048)
			(stroke
				(width 0.1)
				(type default)
			)
			(layer "B.Fab")
		)
		(fp_line
			(start -0.12065 -0.3048)
			(end -0.67945 -0.3048)
			(stroke
				(width 0.1)
				(type default)
			)
			(layer "B.Fab")
		)
		(fp_line
			(start -0.67945 0.3048)
			(end -0.120396 0.3048)
			(stroke
				(width 0.1)
				(type default)
			)
			(layer "B.Fab")
		)
		(fp_line
			(start -0.67945 -0.3048)
			(end -0.67945 0.3048)
			(stroke
				(width 0.1)
				(type default)
			)
			(layer "B.Fab")
		)
		(pad "1" smd circle
			(at 0.40005 0)
			(size 0 0)
			(layers "B.Cu" "B.Mask" "B.Paste")
			(net "SMB_BIC_I2C6_MUX_FRU_R_SCL")
		)
		(pad "2" smd circle
			(at -0.40005 0)
			(size 0 0)
			(layers "B.Cu" "B.Mask" "B.Paste")
			(net "SMB_ISO_CB_SCL")
		)
	)
	(footprint ""
		(layer "B.Cu")
		(at 176.258474 -286.399732 90)
		(property "Reference" "C3130"
			(at 0 0 90)
			(layer "B.SilkS")
			(hide yes)
			(effects
				(font
					(size 1.27 1.27)
				)
				(justify mirror)
			)
		)
		(property "Value" ""
			(at 0 0 90)
			(layer "B.Fab")
			(effects
				(font
					(size 1.27 1.27)
				)
				(justify mirror)
			)
		)
		(duplicate_pad_numbers_are_jumpers no)
		(fp_line
			(start 0.299974 -0.150114)
			(end -0.299974 -0.150114)
			(stroke
				(width 0.1)
				(type default)
			)
			(layer "B.Fab")
		)
		(fp_line
			(start -0.299974 -0.150114)
			(end -0.299974 0.150114)
			(stroke
				(width 0.1)
				(type default)
			)
			(layer "B.Fab")
		)
		(fp_line
			(start 0.299974 0.150114)
			(end 0.299974 -0.150114)
			(stroke
				(width 0.1)
				(type default)
			)
			(layer "B.Fab")
		)
		(fp_line
			(start -0.299974 0.150114)
			(end 0.299974 0.150114)
			(stroke
				(width 0.1)
				(type default)
			)
			(layer "B.Fab")
		)
		(pad "1" smd rect
			(at 0.2667 0 270)
			(size 0.3048 0.381)
			(layers "B.Cu" "B.Mask" "B.Paste")
			(net "P1V25_SERDES_VDDPLL_PEX1")
		)
		(pad "2" smd rect
			(at -0.2667 0 270)
			(size 0.3048 0.381)
			(layers "B.Cu" "B.Mask" "B.Paste")
			(net "GND")
		)
	)
	(footprint ""
		(layer "B.Cu")
		(at 213.806024 18.035524 180)
		(property "Reference" "DE02F_1"
			(at 3.6068 -2.962148 180)
			(unlocked yes)
			(layer "B.SilkS")
			(effects
				(font
					(size 0.7874 0.5842)
					(thickness 0.1524)
				)
				(justify left mirror)
			)
		)
		(property "Value" ""
			(at 0 0 0)
			(layer "B.Fab")
			(effects
				(font
					(size 1.27 1.27)
				)
				(justify mirror)
			)
		)
		(duplicate_pad_numbers_are_jumpers no)
		(fp_line
			(start 1.2192 2.1082)
			(end 1.2192 -2.1082)
			(stroke
				(width 0.1524)
				(type default)
			)
			(layer "B.SilkS")
		)
		(fp_line
			(start 1.2192 -2.1082)
			(end -1.2192 -2.1082)
			(stroke
				(width 0.1524)
				(type default)
			)
			(layer "B.SilkS")
		)
		(fp_line
			(start -1.2192 2.1082)
			(end 1.2192 2.1082)
			(stroke
				(width 0.1524)
				(type default)
			)
			(layer "B.SilkS")
		)
		(fp_line
			(start -1.2192 -2.1082)
			(end -1.2192 2.1082)
			(stroke
				(width 0.1524)
				(type default)
			)
			(layer "B.SilkS")
		)
		(pad "" np_thru_hole circle
			(at -3.4671 -1.27 90)
			(size 1.0414 1.0414)
			(drill 1.0414)
			(layers "*.Cu" "*.Mask")
			(clearance 0.381)
			(thermal_gap 0.381)
		)
		(pad "" np_thru_hole circle
			(at -3.4671 1.27 90)
			(size 1.0414 1.0414)
			(drill 1.0414)
			(layers "*.Cu" "*.Mask")
			(clearance 0.381)
			(thermal_gap 0.381)
		)
		(pad "" np_thru_hole circle
			(at 2.8829 -1.27 90)
			(size 1.0414 1.0414)
			(drill 1.0414)
			(layers "*.Cu" "*.Mask")
			(clearance 0.381)
			(thermal_gap 0.381)
		)
		(pad "" np_thru_hole circle
			(at 2.8829 1.27 90)
			(size 1.0414 1.0414)
			(drill 1.0414)
			(layers "*.Cu" "*.Mask")
			(clearance 0.381)
			(thermal_gap 0.381)
		)
		(pad "1" smd rect
			(at -0.8255 -0.249936 90)
			(size 0.3048 0.508)
			(layers "B.Cu" "B.Mask" "B.Paste")
			(net "85_5INCH_BOTTOM_DN")
		)
		(pad "2" smd rect
			(at -0.8255 0.249936 90)
			(size 0.3048 0.508)
			(layers "B.Cu" "B.Mask" "B.Paste")
			(net "85_5INCH_BOTTOM_DP")
		)
		(pad "3" smd circle
			(at 0 0)
			(size 0 0)
			(layers "B.Cu" "B.Mask" "B.Paste")
			(net "COUPON_GND2")
		)
		(zone
			(layers "F.Cu" "B.Cu" "In1.Cu" "In2.Cu" "In3.Cu" "In4.Cu" "In5.Cu" "In6.Cu"
				"In7.Cu" "In8.Cu" "In9.Cu" "In10.Cu" "In11.Cu" "In12.Cu" "In13.Cu" "In14.Cu"
				"In15.Cu" "In16.Cu"
			)
			(hatch none 0.5)
			(connect_pads
				(clearance 0)
			)
			(min_thickness 0.25)
			(keepout
				(tracks not_allowed)
				(vias allowed)
				(pads allowed)
				(copperpour not_allowed)
				(footprints allowed)
			)
			(placement
				(enabled no)
				(sheetname "")
			)
			(fill
				(thermal_gap 0.5)
				(thermal_bridge_width 0.5)
				(island_removal_mode 0)
			)
			(polygon
				(pts
					(arc
						(start 211.850224 16.765524)
						(mid 209.996024 16.765524)
						(end 211.850224 16.765524)
					)
				)
			)
		)
		(zone
			(layers "F.Cu" "B.Cu" "In1.Cu" "In2.Cu" "In3.Cu" "In4.Cu" "In5.Cu" "In6.Cu"
				"In7.Cu" "In8.Cu" "In9.Cu" "In10.Cu" "In11.Cu" "In12.Cu" "In13.Cu" "In14.Cu"
				"In15.Cu" "In16.Cu"
			)
			(hatch none 0.5)
			(connect_pads
				(clearance 0)
			)
			(min_thickness 0.25)
			(keepout
				(tracks not_allowed)
				(vias allowed)
				(pads allowed)
				(copperpour not_allowed)
				(footprints allowed)
			)
			(placement
				(enabled no)
				(sheetname "")
			)
			(fill
				(thermal_gap 0.5)
				(thermal_bridge_width 0.5)
				(island_removal_mode 0)
			)
			(polygon
				(pts
					(arc
						(start 211.850224 19.305524)
						(mid 209.996024 19.305524)
						(end 211.850224 19.305524)
					)
				)
			)
		)
		(zone
			(layers "F.Cu" "B.Cu" "In1.Cu" "In2.Cu" "In3.Cu" "In4.Cu" "In5.Cu" "In6.Cu"
				"In7.Cu" "In8.Cu" "In9.Cu" "In10.Cu" "In11.Cu" "In12.Cu" "In13.Cu" "In14.Cu"
				"In15.Cu" "In16.Cu"
			)
			(hatch none 0.5)
			(connect_pads
				(clearance 0)
			)
			(min_thickness 0.25)
			(keepout
				(tracks not_allowed)
				(vias allowed)
				(pads allowed)
				(copperpour not_allowed)
				(footprints allowed)
			)
			(placement
				(enabled no)
				(sheetname "")
			)
			(fill
				(thermal_gap 0.5)
				(thermal_bridge_width 0.5)
				(island_removal_mode 0)
			)
			(polygon
				(pts
					(arc
						(start 218.200224 16.765524)
						(mid 216.346024 16.765524)
						(end 218.200224 16.765524)
					)
				)
			)
		)
		(zone
			(layers "F.Cu" "B.Cu" "In1.Cu" "In2.Cu" "In3.Cu" "In4.Cu" "In5.Cu" "In6.Cu"
				"In7.Cu" "In8.Cu" "In9.Cu" "In10.Cu" "In11.Cu" "In12.Cu" "In13.Cu" "In14.Cu"
				"In15.Cu" "In16.Cu"
			)
			(hatch none 0.5)
			(connect_pads
				(clearance 0)
			)
			(min_thickness 0.25)
			(keepout
				(tracks not_allowed)
				(vias allowed)
				(pads allowed)
				(copperpour not_allowed)
				(footprints allowed)
			)
			(placement
				(enabled no)
				(sheetname "")
			)
			(fill
				(thermal_gap 0.5)
				(thermal_bridge_width 0.5)
				(island_removal_mode 0)
			)
			(polygon
				(pts
					(arc
						(start 218.200224 19.305524)
						(mid 216.346024 19.305524)
						(end 218.200224 19.305524)
					)
				)
			)
		)
		(zone
			(layer "B.Cu")
			(hatch none 0.5)
			(connect_pads
				(clearance 0)
			)
			(min_thickness 0.25)
			(keepout
				(tracks not_allowed)
				(vias allowed)
				(pads allowed)
				(copperpour not_allowed)
				(footprints allowed)
			)
			(placement
				(enabled no)
				(sheetname "")
			)
			(fill
				(thermal_gap 0.5)
				(thermal_bridge_width 0.5)
				(island_removal_mode 0)
			)
			(polygon
				(pts
					(xy 214.923624 18.584164) (xy 214.923624 18.48866) (xy 214.326724 18.48866) (xy 214.326724 18.08226)
					(xy 214.923624 18.08226) (xy 214.923624 17.988788) (xy 214.326724 17.988788) (xy 214.326724 17.582388)
					(xy 214.923624 17.582388) (xy 214.923624 17.486884) (xy 214.225124 17.486884) (xy 214.225124 18.584164)
				)
			)
		)
	)
	(footprint ""
		(layer "B.Cu")
		(at 187.149994 -296.37482 180)
		(property "Reference" "C3102"
			(at 0 0 0)
			(layer "B.SilkS")
			(hide yes)
			(effects
				(font
					(size 1.27 1.27)
				)
				(justify mirror)
			)
		)
		(property "Value" ""
			(at 0 0 0)
			(layer "B.Fab")
			(effects
				(font
					(size 1.27 1.27)
				)
				(justify mirror)
			)
		)
		(duplicate_pad_numbers_are_jumpers no)
		(fp_line
			(start 0.299974 0.150114)
			(end 0.299974 -0.150114)
			(stroke
				(width 0.1)
				(type default)
			)
			(layer "B.Fab")
		)
		(fp_line
			(start 0.299974 -0.150114)
			(end -0.299974 -0.150114)
			(stroke
				(width 0.1)
				(type default)
			)
			(layer "B.Fab")
		)
		(fp_line
			(start -0.299974 0.150114)
			(end 0.299974 0.150114)
			(stroke
				(width 0.1)
				(type default)
			)
			(layer "B.Fab")
		)
		(fp_line
			(start -0.299974 -0.150114)
			(end -0.299974 0.150114)
			(stroke
				(width 0.1)
				(type default)
			)
			(layer "B.Fab")
		)
		(pad "1" smd rect
			(at 0.2667 0)
			(size 0.3048 0.381)
			(layers "B.Cu" "B.Mask" "B.Paste")
			(net "P1V25_PEX1")
		)
		(pad "2" smd rect
			(at -0.2667 0)
			(size 0.3048 0.381)
			(layers "B.Cu" "B.Mask" "B.Paste")
			(net "GND")
		)
	)
)
